# T6G (Grand Teton) — schematic netlist excerpt (pin names and nets, part order shuffled) for the footprints in the layout excerpt that follows; sources: Cadence DE-HDL packaged netlist, KiCad conversion of 04192023_DAF0TMB3IC0_F0TG_MB_C_brd_V02_OCP.brd

R3341  Q_RES  33.2 1% CHIP  pkg 0402LF  page 151 : A = SMB_HOST_CLK_3V3AUX_SDA ; B = SMB_HOST_CLK_GEN2_3V3AUX_SDA
PR3935  Q_RES  10K 1% CHIP  pkg 0402LF  page 262 : A = HSC_VTEMP ; B = AGND_HSC
R866  Q_RES  10K 1% CHIP  pkg 0201LF  page 342 : A = RST_RT_CPU1_P2_PERST_R_N ; B = GND

(kicad_pcb
	(version 20260206)
	(generator "pcbnew")
	(generator_version "10.0")
	(general
		(thickness 1.6)
		(legacy_teardrops no)
	)
	(paper "A4")
	(title_block
		(title "04192023_DAF0TMB3IC0_F0TG_MB_C_brd_V02_OCP.brd")
		(comment 1 "Grand Teton / footprints 2418-2420 of 8354")
	)
	(layers
		(0 "F.Cu" signal "TOP")
		(4 "In1.Cu" signal "GND")
		(6 "In2.Cu" signal "IN1")
		(8 "In3.Cu" signal "GND1")
		(10 "In4.Cu" signal "IN2")
		(12 "In5.Cu" signal "GND2")
		(14 "In6.Cu" signal "IN3")
		(16 "In7.Cu" signal "GND3")
		(18 "In8.Cu" signal "VCC")
		(20 "In9.Cu" signal "VCC1")
		(22 "In10.Cu" signal "GND4")
		(24 "In11.Cu" signal "IN4")
		(26 "In12.Cu" signal "GND5")
		(28 "In13.Cu" signal "IN5")
		(30 "In14.Cu" signal "GND6")
		(32 "In15.Cu" signal "IN6")
		(34 "In16.Cu" signal "GND7")
		(2 "B.Cu" signal "BOTTOM")
		(9 "F.Adhes" user "F.Adhesive")
		(11 "B.Adhes" user "B.Adhesive")
		(13 "F.Paste" user "Package Geometry/Pastemask Top")
		(15 "B.Paste" user "Package Geometry/Pastemask Bottom")
		(5 "F.SilkS" user "Ref Des/Silkscreen Top")
		(7 "B.SilkS" user "Ref Des/Silkscreen Bottom")
		(1 "F.Mask" user "Board Geometry/Soldermask Top")
		(3 "B.Mask" user "Board Geometry/Soldermask Bottom")
		(17 "Dwgs.User" user "User.Drawings")
		(19 "Cmts.User" user "User.Comments")
		(21 "Eco1.User" user "User.Eco1")
		(23 "Eco2.User" user "User.Eco2")
		(25 "Edge.Cuts" user "Board Geometry/Outline")
		(27 "Margin" user)
		(31 "F.CrtYd" user "Package Geometry/Place Bound Top")
		(29 "B.CrtYd" user "Package Geometry/Place Bound Bottom")
		(35 "F.Fab" user "Ref Des/Assembly Top")
		(33 "B.Fab" user "Ref Des/Assembly Bottom")
	)
	(footprint ""
		(layer "F.Cu")
		(at 178.71694 -404.500842 180)
		(property "Reference" "PR3935"
			(at 0 0 180)
			(layer "F.SilkS")
			(hide yes)
			(effects
				(font
					(size 1.27 1.27)
				)
			)
		)
		(property "Value" ""
			(at 0 0 180)
			(layer "F.Fab")
			(effects
				(font
					(size 1.27 1.27)
				)
			)
		)
		(duplicate_pad_numbers_are_jumpers no)
		(fp_line
			(start 0.7874 0.4064)
			(end -0.7874 0.4064)
			(stroke
				(width 0.1524)
				(type default)
			)
			(layer "F.SilkS")
		)
		(fp_line
			(start 0.7874 -0.4064)
			(end 0.7874 0.4064)
			(stroke
				(width 0.1524)
				(type default)
			)
			(layer "F.SilkS")
		)
		(fp_line
			(start -0.7874 0.4064)
			(end -0.7874 -0.4064)
			(stroke
				(width 0.1524)
				(type default)
			)
			(layer "F.SilkS")
		)
		(fp_line
			(start -0.7874 -0.4064)
			(end 0.7874 -0.4064)
			(stroke
				(width 0.1524)
				(type default)
			)
			(layer "F.SilkS")
		)
		(fp_line
			(start 0.67945 0.3048)
			(end 0.120396 0.3048)
			(stroke
				(width 0.1)
				(type default)
			)
			(layer "F.Fab")
		)
		(fp_line
			(start 0.67945 -0.3048)
			(end 0.67945 0.3048)
			(stroke
				(width 0.1)
				(type default)
			)
			(layer "F.Fab")
		)
		(fp_line
			(start 0.12065 -0.2794)
			(end 0.12065 -0.3048)
			(stroke
				(width 0.1)
				(type default)
			)
			(layer "F.Fab")
		)
		(fp_line
			(start 0.12065 -0.3048)
			(end 0.67945 -0.3048)
			(stroke
				(width 0.1)
				(type default)
			)
			(layer "F.Fab")
		)
		(fp_line
			(start 0.120396 0.3048)
			(end 0.120396 0.2794)
			(stroke
				(width 0.1)
				(type default)
			)
			(layer "F.Fab")
		)
		(fp_line
			(start 0.120396 0.2794)
			(end -0.12065 0.2794)
			(stroke
				(width 0.1)
				(type default)
			)
			(layer "F.Fab")
		)
		(fp_line
			(start -0.12065 0.3048)
			(end -0.67945 0.3048)
			(stroke
				(width 0.1)
				(type default)
			)
			(layer "F.Fab")
		)
		(fp_line
			(start -0.12065 0.2794)
			(end -0.12065 0.3048)
			(stroke
				(width 0.1)
				(type default)
			)
			(layer "F.Fab")
		)
		(fp_line
			(start -0.12065 -0.2794)
			(end 0.12065 -0.2794)
			(stroke
				(width 0.1)
				(type default)
			)
			(layer "F.Fab")
		)
		(fp_line
			(start -0.12065 -0.305054)
			(end -0.12065 -0.2794)
			(stroke
				(width 0.1)
				(type default)
			)
			(layer "F.Fab")
		)
		(fp_line
			(start -0.67945 0.3048)
			(end -0.67945 -0.305054)
			(stroke
				(width 0.1)
				(type default)
			)
			(layer "F.Fab")
		)
		(fp_line
			(start -0.67945 -0.305054)
			(end -0.12065 -0.305054)
			(stroke
				(width 0.1)
				(type default)
			)
			(layer "F.Fab")
		)
		(pad "1" smd circle
			(at -0.40005 0 180)
			(size 0 0)
			(layers "F.Cu" "F.Mask" "F.Paste")
			(net "HSC_VTEMP")
		)
		(pad "2" smd circle
			(at 0.40005 0 180)
			(size 0 0)
			(layers "F.Cu" "F.Mask" "F.Paste")
			(net "AGND_HSC")
		)
	)
	(footprint ""
		(layer "F.Cu")
		(at 167.79621 -394.3604 -90)
		(property "Reference" "R866"
			(at 0 0 270)
			(layer "F.SilkS")
			(hide yes)
			(effects
				(font
					(size 1.27 1.27)
				)
			)
		)
		(property "Value" ""
			(at 0 0 270)
			(layer "F.Fab")
			(effects
				(font
					(size 1.27 1.27)
				)
			)
		)
		(duplicate_pad_numbers_are_jumpers no)
		(fp_line
			(start -0.32512 0.175006)
			(end -0.32512 -0.175006)
			(stroke
				(width 0.1)
				(type default)
			)
			(layer "F.Fab")
		)
		(fp_line
			(start 0.32512 0.175006)
			(end -0.32512 0.175006)
			(stroke
				(width 0.1)
				(type default)
			)
			(layer "F.Fab")
		)
		(fp_line
			(start -0.32512 -0.175006)
			(end 0.32512 -0.175006)
			(stroke
				(width 0.1)
				(type default)
			)
			(layer "F.Fab")
		)
		(fp_line
			(start 0.32512 -0.175006)
			(end 0.32512 0.175006)
			(stroke
				(width 0.1)
				(type default)
			)
			(layer "F.Fab")
		)
		(pad "1" smd rect
			(at -0.2667 0 270)
			(size 0.3048 0.381)
			(layers "F.Cu" "F.Mask" "F.Paste")
			(net "RST_RT_CPU1_P2_PERST_R_N")
		)
		(pad "2" smd rect
			(at 0.2667 0 90)
			(size 0.3048 0.381)
			(layers "F.Cu" "F.Mask" "F.Paste")
			(net "GND")
		)
	)
	(footprint ""
		(layer "F.Cu")
		(at 13.437108 -128.54559 90)
		(property "Reference" "R3341"
			(at 0 0 90)
			(layer "F.SilkS")
			(hide yes)
			(effects
				(font
					(size 1.27 1.27)
				)
			)
		)
		(property "Value" ""
			(at 0 0 90)
			(layer "F.Fab")
			(effects
				(font
					(size 1.27 1.27)
				)
			)
		)
		(duplicate_pad_numbers_are_jumpers no)
		(fp_line
			(start 0.7874 -0.4064)
			(end 0.7874 0.4064)
			(stroke
				(width 0.1524)
				(type default)
			)
			(layer "F.SilkS")
		)
		(fp_line
			(start -0.7874 -0.4064)
			(end 0.7874 -0.4064)
			(stroke
				(width 0.1524)
				(type default)
			)
			(layer "F.SilkS")
		)
		(fp_line
			(start 0.7874 0.4064)
			(end -0.7874 0.4064)
			(stroke
				(width 0.1524)
				(type default)
			)
			(layer "F.SilkS")
		)
		(fp_line
			(start -0.7874 0.4064)
			(end -0.7874 -0.4064)
			(stroke
				(width 0.1524)
				(type default)
			)
			(layer "F.SilkS")
		)
		(fp_line
			(start -0.12065 -0.305054)
			(end -0.12065 -0.2794)
			(stroke
				(width 0.1)
				(type default)
			)
			(layer "F.Fab")
		)
		(fp_line
			(start -0.67945 -0.305054)
			(end -0.12065 -0.305054)
			(stroke
				(width 0.1)
				(type default)
			)
			(layer "F.Fab")
		)
		(fp_line
			(start 0.67945 -0.3048)
			(end 0.67945 0.3048)
			(stroke
				(width 0.1)
				(type default)
			)
			(layer "F.Fab")
		)
		(fp_line
			(start 0.12065 -0.3048)
			(end 0.67945 -0.3048)
			(stroke
				(width 0.1)
				(type default)
			)
			(layer "F.Fab")
		)
		(fp_line
			(start 0.12065 -0.2794)
			(end 0.12065 -0.3048)
			(stroke
				(width 0.1)
				(type default)
			)
			(layer "F.Fab")
		)
		(fp_line
			(start -0.12065 -0.2794)
			(end 0.12065 -0.2794)
			(stroke
				(width 0.1)
				(type default)
			)
			(layer "F.Fab")
		)
		(fp_line
			(start 0.120396 0.2794)
			(end -0.12065 0.2794)
			(stroke
				(width 0.1)
				(type default)
			)
			(layer "F.Fab")
		)
		(fp_line
			(start -0.12065 0.2794)
			(end -0.12065 0.3048)
			(stroke
				(width 0.1)
				(type default)
			)
			(layer "F.Fab")
		)
		(fp_line
			(start 0.67945 0.3048)
			(end 0.120396 0.3048)
			(stroke
				(width 0.1)
				(type default)
			)
			(layer "F.Fab")
		)
		(fp_line
			(start 0.120396 0.3048)
			(end 0.120396 0.2794)
			(stroke
				(width 0.1)
				(type default)
			)
			(layer "F.Fab")
		)
		(fp_line
			(start -0.12065 0.3048)
			(end -0.67945 0.3048)
			(stroke
				(width 0.1)
				(type default)
			)
			(layer "F.Fab")
		)
		(fp_line
			(start -0.67945 0.3048)
			(end -0.67945 -0.305054)
			(stroke
				(width 0.1)
				(type default)
			)
			(layer "F.Fab")
		)
		(pad "1" smd circle
			(at -0.40005 0 90)
			(size 0 0)
			(layers "F.Cu" "F.Mask" "F.Paste")
			(net "SMB_HOST_CLK_3V3AUX_SDA")
		)
		(pad "2" smd circle
			(at 0.40005 0 90)
			(size 0 0)
			(layers "F.Cu" "F.Mask" "F.Paste")
			(net "SMB_HOST_CLK_GEN2_3V3AUX_SDA")
		)
	)
)
